(kicad_pcb
	(version 20260206)
	(generator "pcbnew")
	(generator_version "10.0")
	(general
		(thickness 1.6)
		(legacy_teardrops no)
	)
	(paper "A4")
	(title_block
		(title "baseboard — 13948-1b.1110WZS1818.brd")
		(comment 1 "Honey Badger (Wiwynn) / footprints 2454-2460 of 2523")
	)
	(layers
		(0 "F.Cu" signal "TOP")
		(4 "In1.Cu" signal "L2GND")
		(6 "In2.Cu" signal "L3")
		(8 "In3.Cu" signal "L4VCC")
		(10 "In4.Cu" signal "L5VCC")
		(12 "In5.Cu" signal "L6")
		(14 "In6.Cu" signal "L7GND")
		(2 "B.Cu" signal "BOTTOM")
		(9 "F.Adhes" user "F.Adhesive")
		(11 "B.Adhes" user "B.Adhesive")
		(13 "F.Paste" user "Package Geometry/Pastemask Top")
		(15 "B.Paste" user "Package Geometry/Pastemask Bottom")
		(5 "F.SilkS" user "Ref Des/Silkscreen Top")
		(7 "B.SilkS" user "Ref Des/Silkscreen Bottom")
		(1 "F.Mask" user "Board Geometry/Soldermask Top")
		(3 "B.Mask" user "Board Geometry/Soldermask Bottom")
		(17 "Dwgs.User" user "User.Drawings")
		(19 "Cmts.User" user "User.Comments")
		(21 "Eco1.User" user "User.Eco1")
		(23 "Eco2.User" user "User.Eco2")
		(25 "Edge.Cuts" user "Board Geometry/Outline")
		(27 "Margin" user)
		(31 "F.CrtYd" user "Package Geometry/Place Bound Top")
		(29 "B.CrtYd" user "Package Geometry/Place Bound Bottom")
		(35 "F.Fab" user "Ref Des/Assembly Top")
		(33 "B.Fab" user "Ref Des/Assembly Bottom")
	)
	(footprint ""
		(layer "B.Cu")
		(at 297.2562 -203.962 180)
		(property "Reference" "C182"
			(at 0 0 0)
			(layer "B.SilkS")
			(hide yes)
			(effects
				(font
					(size 1.27 1.27)
				)
				(justify mirror)
			)
		)
		(property "Value" "SCD1U16V2KX-3GP"
			(at -1.1811 -2.7051 180)
			(unlocked yes)
			(layer "B.Fab")
			(hide yes)
			(effects
				(font
					(size 1.016 1.016)
					(thickness 0.1524)
				)
				(justify mirror)
			)
		)
		(property "Device Type" "C402H22"
			(at -1.1811 -4.2291 180)
			(unlocked yes)
			(layer "B.Fab")
			(hide yes)
			(effects
				(font
					(size 1.016 1.016)
					(thickness 0.1524)
				)
				(justify mirror)
			)
		)
		(duplicate_pad_numbers_are_jumpers no)
		(fp_rect
			(start 0.4318 0.9525)
			(end -0.4318 -0.9525)
			(stroke
				(width 0)
				(type default)
			)
			(fill no)
			(layer "B.CrtYd")
		)
		(fp_rect
			(start 0.4318 0.9525)
			(end -0.4318 -0.9525)
			(stroke
				(width 0)
				(type default)
			)
			(fill no)
			(layer "B.Fab")
		)
		(pad "1" smd custom
			(at 0 -0.4445)
			(size 0.1524 0.1524)
			(layers "B.Cu" "B.Mask" "B.Paste")
			(net "P1V53_STBY")
			(options
				(clearance outline)
				(anchor circle)
			)
			(primitives
				(gr_poly
					(pts
						(arc
							(start 0.3048 0.2032)
							(mid 0.275042 0.275042)
							(end 0.2032 0.3048)
						)
						(arc
							(start -0.2032 0.3048)
							(mid -0.275042 0.275042)
							(end -0.3048 0.2032)
						)
						(arc
							(start -0.3048 -0.2032)
							(mid -0.275042 -0.275042)
							(end -0.2032 -0.3048)
						)
						(arc
							(start 0.2032 -0.3048)
							(mid 0.275042 -0.275042)
							(end 0.3048 -0.2032)
						)
					)
					(width 0)
					(fill yes)
				)
			)
		)
		(pad "2" smd custom
			(at 0 0.4445)
			(size 0.1524 0.1524)
			(layers "B.Cu" "B.Mask" "B.Paste")
			(net "GND")
			(options
				(clearance outline)
				(anchor circle)
			)
			(primitives
				(gr_poly
					(pts
						(arc
							(start 0.3048 0.2032)
							(mid 0.275042 0.275042)
							(end 0.2032 0.3048)
						)
						(arc
							(start -0.2032 0.3048)
							(mid -0.275042 0.275042)
							(end -0.3048 0.2032)
						)
						(arc
							(start -0.3048 -0.2032)
							(mid -0.275042 -0.275042)
							(end -0.2032 -0.3048)
						)
						(arc
							(start 0.2032 -0.3048)
							(mid 0.275042 -0.275042)
							(end 0.3048 -0.2032)
						)
					)
					(width 0)
					(fill yes)
				)
			)
		)
	)
	(footprint ""
		(layer "B.Cu")
		(at 105.188766 -54.52872 -90)
		(property "Reference" "SC1011"
			(at 0 0 90)
			(layer "B.SilkS")
			(hide yes)
			(effects
				(font
					(size 1.27 1.27)
				)
				(justify mirror)
			)
		)
		(property "Value" "SC1KP50V2KX-1GP"
			(at -1.1811 -2.7051 270)
			(unlocked yes)
			(layer "B.Fab")
			(hide yes)
			(effects
				(font
					(size 1.016 1.016)
					(thickness 0.1524)
				)
				(justify mirror)
			)
		)
		(property "Device Type" "C402H22"
			(at -1.1811 -4.2291 270)
			(unlocked yes)
			(layer "B.Fab")
			(hide yes)
			(effects
				(font
					(size 1.016 1.016)
					(thickness 0.1524)
				)
				(justify mirror)
			)
		)
		(duplicate_pad_numbers_are_jumpers no)
		(fp_rect
			(start 0.4318 0.9525)
			(end -0.4318 -0.9525)
			(stroke
				(width 0)
				(type default)
			)
			(fill no)
			(layer "B.CrtYd")
		)
		(fp_rect
			(start 0.4318 0.9525)
			(end -0.4318 -0.9525)
			(stroke
				(width 0)
				(type default)
			)
			(fill no)
			(layer "B.Fab")
		)
		(pad "1" smd custom
			(at 0 -0.4445 90)
			(size 0.1524 0.1524)
			(layers "B.Cu" "B.Mask" "B.Paste")
			(net "P1V8_C")
			(options
				(clearance outline)
				(anchor circle)
			)
			(primitives
				(gr_poly
					(pts
						(arc
							(start 0.3048 0.2032)
							(mid 0.275042 0.275042)
							(end 0.2032 0.3048)
						)
						(arc
							(start -0.2032 0.3048)
							(mid -0.275042 0.275042)
							(end -0.3048 0.2032)
						)
						(arc
							(start -0.3048 -0.2032)
							(mid -0.275042 -0.275042)
							(end -0.2032 -0.3048)
						)
						(arc
							(start 0.2032 -0.3048)
							(mid 0.275042 -0.275042)
							(end 0.3048 -0.2032)
						)
					)
					(width 0)
					(fill yes)
				)
			)
		)
		(pad "2" smd custom
			(at 0 0.4445 90)
			(size 0.1524 0.1524)
			(layers "B.Cu" "B.Mask" "B.Paste")
			(net "GND")
			(options
				(clearance outline)
				(anchor circle)
			)
			(primitives
				(gr_poly
					(pts
						(arc
							(start 0.3048 0.2032)
							(mid 0.275042 0.275042)
							(end 0.2032 0.3048)
						)
						(arc
							(start -0.2032 0.3048)
							(mid -0.275042 0.275042)
							(end -0.3048 0.2032)
						)
						(arc
							(start -0.3048 -0.2032)
							(mid -0.275042 -0.275042)
							(end -0.2032 -0.3048)
						)
						(arc
							(start 0.2032 -0.3048)
							(mid 0.275042 -0.275042)
							(end 0.3048 -0.2032)
						)
					)
					(width 0)
					(fill yes)
				)
			)
		)
	)
	(footprint ""
		(layer "B.Cu")
		(at 112.630966 -26.416 -90)
		(property "Reference" "SQ2"
			(at 0 0 90)
			(layer "B.SilkS")
			(hide yes)
			(effects
				(font
					(size 1.27 1.27)
				)
				(justify mirror)
			)
		)
		(property "Value" "AO3400A-GP"
			(at -0.0254 -12.3444 270)
			(unlocked yes)
			(layer "B.Fab")
			(hide yes)
			(effects
				(font
					(size 1.016 1.016)
					(thickness 0.1524)
				)
				(justify mirror)
			)
		)
		(property "Device Type" "SOT23DGS2D8H50"
			(at -0.0254 -14.2494 270)
			(unlocked yes)
			(layer "B.Fab")
			(hide yes)
			(effects
				(font
					(size 1.016 1.016)
					(thickness 0.1524)
				)
				(justify mirror)
			)
		)
		(duplicate_pad_numbers_are_jumpers no)
		(fp_line
			(start -1.7018 0.254)
			(end 1.7018 0.254)
			(stroke
				(width 0.1524)
				(type default)
			)
			(layer "B.SilkS")
		)
		(fp_line
			(start 1.7018 0.254)
			(end 1.7018 -0.254)
			(stroke
				(width 0.1524)
				(type default)
			)
			(layer "B.SilkS")
		)
		(fp_line
			(start -1.7018 -0.254)
			(end -1.7018 0.254)
			(stroke
				(width 0.1524)
				(type default)
			)
			(layer "B.SilkS")
		)
		(fp_line
			(start 1.7018 -0.254)
			(end -1.7018 -0.254)
			(stroke
				(width 0.1524)
				(type default)
			)
			(layer "B.SilkS")
		)
		(fp_rect
			(start 1.778 1.9812)
			(end -1.778 -1.9812)
			(stroke
				(width 0)
				(type default)
			)
			(fill no)
			(layer "B.CrtYd")
		)
		(fp_poly
			(pts
				(xy 1.778 -1.9812) (xy -1.778 -1.9812) (xy -1.778 1.9812) (xy 1.778 1.9812)
			)
			(stroke
				(width 0)
				(type default)
			)
			(fill no)
			(layer "B.Fab")
		)
		(pad "D" smd custom
			(at 0 -1.1176 90)
			(size 0.254 0.254)
			(layers "B.Cu" "B.Mask" "B.Paste")
			(net "SYS_ERROR_LED_D")
			(options
				(clearance outline)
				(anchor circle)
			)
			(primitives
				(gr_poly
					(pts
						(arc
							(start -0.508 0.4064)
							(mid -0.448484 0.550084)
							(end -0.3048 0.6096)
						)
						(arc
							(start 0.3048 0.6096)
							(mid 0.448484 0.550084)
							(end 0.508 0.4064)
						)
						(arc
							(start 0.508 -0.4064)
							(mid 0.448484 -0.550084)
							(end 0.3048 -0.6096)
						)
						(arc
							(start -0.3048 -0.6096)
							(mid -0.448484 -0.550084)
							(end -0.508 -0.4064)
						)
					)
					(width 0)
					(fill yes)
				)
			)
		)
		(pad "G" smd custom
			(at 1.016 1.1176 90)
			(size 0.254 0.254)
			(layers "B.Cu" "B.Mask" "B.Paste")
			(net "SYS_ERR_0")
			(options
				(clearance outline)
				(anchor circle)
			)
			(primitives
				(gr_poly
					(pts
						(arc
							(start -0.508 0.4064)
							(mid -0.448484 0.550084)
							(end -0.3048 0.6096)
						)
						(arc
							(start 0.3048 0.6096)
							(mid 0.448484 0.550084)
							(end 0.508 0.4064)
						)
						(arc
							(start 0.508 -0.4064)
							(mid 0.448484 -0.550084)
							(end 0.3048 -0.6096)
						)
						(arc
							(start -0.3048 -0.6096)
							(mid -0.448484 -0.550084)
							(end -0.508 -0.4064)
						)
					)
					(width 0)
					(fill yes)
				)
			)
		)
		(pad "S" smd custom
			(at -1.016 1.1176 90)
			(size 0.254 0.254)
			(layers "B.Cu" "B.Mask" "B.Paste")
			(net "GND")
			(options
				(clearance outline)
				(anchor circle)
			)
			(primitives
				(gr_poly
					(pts
						(arc
							(start -0.508 0.4064)
							(mid -0.448484 0.550084)
							(end -0.3048 0.6096)
						)
						(arc
							(start 0.3048 0.6096)
							(mid 0.448484 0.550084)
							(end 0.508 0.4064)
						)
						(arc
							(start 0.508 -0.4064)
							(mid 0.448484 -0.550084)
							(end 0.3048 -0.6096)
						)
						(arc
							(start -0.3048 -0.6096)
							(mid -0.448484 -0.550084)
							(end -0.508 -0.4064)
						)
					)
					(width 0)
					(fill yes)
				)
			)
		)
	)
	(footprint ""
		(layer "B.Cu")
		(at 79.229966 -55.753 -90)
		(property "Reference" "SC926"
			(at 0 0 90)
			(layer "B.SilkS")
			(hide yes)
			(effects
				(font
					(size 1.27 1.27)
				)
				(justify mirror)
			)
		)
		(property "Value" "SCD1U6D3V1KX-GP"
			(at 2.8321 -1.7399 270)
			(unlocked yes)
			(layer "B.Fab")
			(hide yes)
			(effects
				(font
					(size 1.016 1.016)
					(thickness 0.1524)
				)
				(justify mirror)
			)
		)
		(property "Device Type" "C0201H13"
			(at 2.8321 -3.2639 270)
			(unlocked yes)
			(layer "B.Fab")
			(hide yes)
			(effects
				(font
					(size 1.016 1.016)
					(thickness 0.1524)
				)
				(justify mirror)
			)
		)
		(duplicate_pad_numbers_are_jumpers no)
		(fp_rect
			(start 0.2794 0.6477)
			(end -0.2794 -0.6477)
			(stroke
				(width 0)
				(type default)
			)
			(fill no)
			(layer "B.CrtYd")
		)
		(fp_rect
			(start 0.2794 0.6477)
			(end -0.2794 -0.6477)
			(stroke
				(width 0)
				(type default)
			)
			(fill no)
			(layer "B.Fab")
		)
		(pad "1" smd custom
			(at 0 -0.2794 90)
			(size 0.0762 0.0762)
			(layers "B.Cu" "B.Mask" "B.Paste")
			(net "VDDA_SAS_REF_CLK")
			(options
				(clearance outline)
				(anchor circle)
			)
			(primitives
				(gr_poly
					(pts
						(arc
							(start 0.1524 0.127)
							(mid 0.137521 0.162921)
							(end 0.1016 0.1778)
						)
						(arc
							(start -0.1016 0.1778)
							(mid -0.137521 0.162921)
							(end -0.1524 0.127)
						)
						(arc
							(start -0.1524 -0.127)
							(mid -0.137521 -0.162921)
							(end -0.1016 -0.1778)
						)
						(arc
							(start 0.1016 -0.1778)
							(mid 0.137521 -0.162921)
							(end 0.1524 -0.127)
						)
					)
					(width 0)
					(fill yes)
				)
			)
		)
		(pad "2" smd custom
			(at 0 0.2794 90)
			(size 0.0762 0.0762)
			(layers "B.Cu" "B.Mask" "B.Paste")
			(net "GND")
			(options
				(clearance outline)
				(anchor circle)
			)
			(primitives
				(gr_poly
					(pts
						(arc
							(start 0.1524 0.127)
							(mid 0.137521 0.162921)
							(end 0.1016 0.1778)
						)
						(arc
							(start -0.1016 0.1778)
							(mid -0.137521 0.162921)
							(end -0.1524 0.127)
						)
						(arc
							(start -0.1524 -0.127)
							(mid -0.137521 -0.162921)
							(end -0.1016 -0.1778)
						)
						(arc
							(start 0.1016 -0.1778)
							(mid 0.137521 -0.162921)
							(end 0.1524 -0.127)
						)
					)
					(width 0)
					(fill yes)
				)
			)
		)
	)
	(footprint ""
		(layer "B.Cu")
		(at 114.64417 -100.0506)
		(property "Reference" "SC1139"
			(at 0 0 0)
			(layer "B.SilkS")
			(hide yes)
			(effects
				(font
					(size 1.27 1.27)
				)
				(justify mirror)
			)
		)
		(property "Value" "SCD1U6D3V1KX-GP"
			(at 2.8321 -1.7399 0)
			(unlocked yes)
			(layer "B.Fab")
			(hide yes)
			(effects
				(font
					(size 1.016 1.016)
					(thickness 0.1524)
				)
				(justify mirror)
			)
		)
		(property "Device Type" "C0201H13"
			(at 2.8321 -3.2639 0)
			(unlocked yes)
			(layer "B.Fab")
			(hide yes)
			(effects
				(font
					(size 1.016 1.016)
					(thickness 0.1524)
				)
				(justify mirror)
			)
		)
		(duplicate_pad_numbers_are_jumpers no)
		(fp_rect
			(start 0.2794 0.6477)
			(end -0.2794 -0.6477)
			(stroke
				(width 0)
				(type default)
			)
			(fill no)
			(layer "B.CrtYd")
		)
		(fp_rect
			(start 0.2794 0.6477)
			(end -0.2794 -0.6477)
			(stroke
				(width 0)
				(type default)
			)
			(fill no)
			(layer "B.Fab")
		)
		(pad "1" smd custom
			(at 0 -0.2794 180)
			(size 0.0762 0.0762)
			(layers "B.Cu" "B.Mask" "B.Paste")
			(net "GB_VDDH2")
			(options
				(clearance outline)
				(anchor circle)
			)
			(primitives
				(gr_poly
					(pts
						(arc
							(start 0.1524 0.127)
							(mid 0.137521 0.162921)
							(end 0.1016 0.1778)
						)
						(arc
							(start -0.1016 0.1778)
							(mid -0.137521 0.162921)
							(end -0.1524 0.127)
						)
						(arc
							(start -0.1524 -0.127)
							(mid -0.137521 -0.162921)
							(end -0.1016 -0.1778)
						)
						(arc
							(start 0.1016 -0.1778)
							(mid 0.137521 -0.162921)
							(end 0.1524 -0.127)
						)
					)
					(width 0)
					(fill yes)
				)
			)
		)
		(pad "2" smd custom
			(at 0 0.2794 180)
			(size 0.0762 0.0762)
			(layers "B.Cu" "B.Mask" "B.Paste")
			(net "GND")
			(options
				(clearance outline)
				(anchor circle)
			)
			(primitives
				(gr_poly
					(pts
						(arc
							(start 0.1524 0.127)
							(mid 0.137521 0.162921)
							(end 0.1016 0.1778)
						)
						(arc
							(start -0.1016 0.1778)
							(mid -0.137521 0.162921)
							(end -0.1524 0.127)
						)
						(arc
							(start -0.1524 -0.127)
							(mid -0.137521 -0.162921)
							(end -0.1016 -0.1778)
						)
						(arc
							(start 0.1016 -0.1778)
							(mid 0.137521 -0.162921)
							(end 0.1524 -0.127)
						)
					)
					(width 0)
					(fill yes)
				)
			)
		)
	)
	(footprint ""
		(layer "B.Cu")
		(at 295.3004 -172.5422 90)
		(property "Reference" "C216"
			(at 0 0 90)
			(layer "B.SilkS")
			(hide yes)
			(effects
				(font
					(size 1.27 1.27)
				)
				(justify mirror)
			)
		)
		(property "Value" "SC1U10V2KX-1GP"
			(at -1.1811 -2.7051 90)
			(unlocked yes)
			(layer "B.Fab")
			(hide yes)
			(effects
				(font
					(size 1.016 1.016)
					(thickness 0.1524)
				)
				(justify mirror)
			)
		)
		(property "Device Type" "C402H22"
			(at -1.1811 -4.2291 90)
			(unlocked yes)
			(layer "B.Fab")
			(hide yes)
			(effects
				(font
					(size 1.016 1.016)
					(thickness 0.1524)
				)
				(justify mirror)
			)
		)
		(duplicate_pad_numbers_are_jumpers no)
		(fp_rect
			(start 0.4318 0.9525)
			(end -0.4318 -0.9525)
			(stroke
				(width 0)
				(type default)
			)
			(fill no)
			(layer "B.CrtYd")
		)
		(fp_rect
			(start 0.4318 0.9525)
			(end -0.4318 -0.9525)
			(stroke
				(width 0)
				(type default)
			)
			(fill no)
			(layer "B.Fab")
		)
		(pad "1" smd custom
			(at 0 -0.4445 270)
			(size 0.1524 0.1524)
			(layers "B.Cu" "B.Mask" "B.Paste")
			(net "P3V3_STBY")
			(options
				(clearance outline)
				(anchor circle)
			)
			(primitives
				(gr_poly
					(pts
						(arc
							(start 0.3048 0.2032)
							(mid 0.275042 0.275042)
							(end 0.2032 0.3048)
						)
						(arc
							(start -0.2032 0.3048)
							(mid -0.275042 0.275042)
							(end -0.3048 0.2032)
						)
						(arc
							(start -0.3048 -0.2032)
							(mid -0.275042 -0.275042)
							(end -0.2032 -0.3048)
						)
						(arc
							(start 0.2032 -0.3048)
							(mid 0.275042 -0.275042)
							(end 0.3048 -0.2032)
						)
					)
					(width 0)
					(fill yes)
				)
			)
		)
		(pad "2" smd custom
			(at 0 0.4445 270)
			(size 0.1524 0.1524)
			(layers "B.Cu" "B.Mask" "B.Paste")
			(net "GND")
			(options
				(clearance outline)
				(anchor circle)
			)
			(primitives
				(gr_poly
					(pts
						(arc
							(start 0.3048 0.2032)
							(mid 0.275042 0.275042)
							(end 0.2032 0.3048)
						)
						(arc
							(start -0.2032 0.3048)
							(mid -0.275042 0.275042)
							(end -0.3048 0.2032)
						)
						(arc
							(start -0.3048 -0.2032)
							(mid -0.275042 -0.275042)
							(end -0.2032 -0.3048)
						)
						(arc
							(start 0.2032 -0.3048)
							(mid 0.275042 -0.275042)
							(end 0.3048 -0.2032)
						)
					)
					(width 0)
					(fill yes)
				)
			)
		)
	)
	(footprint ""
		(layer "B.Cu")
		(at 87.38616 -53.086)
		(property "Reference" "SR630"
			(at 0 0 0)
			(layer "B.SilkS")
			(hide yes)
			(effects
				(font
					(size 1.27 1.27)
				)
				(justify mirror)
			)
		)
		(property "Value" "2K2R2F-GP"
			(at -0.064008 -3.993896 0)
			(unlocked yes)
			(layer "B.Fab")
			(hide yes)
			(effects
				(font
					(size 1.016 1.016)
					(thickness 0.1524)
				)
				(justify mirror)
			)
		)
		(property "Device Type" "R402H16"
			(at -0.064008 -5.517896 0)
			(unlocked yes)
			(layer "B.Fab")
			(hide yes)
			(effects
				(font
					(size 1.016 1.016)
					(thickness 0.1524)
				)
				(justify mirror)
			)
		)
		(duplicate_pad_numbers_are_jumpers no)
		(fp_line
			(start -0.508 -0.9398)
			(end 0.508 -0.9398)
			(stroke
				(width 0.1524)
				(type default)
			)
			(layer "B.SilkS")
		)
		(fp_line
			(start 0.508 -0.9398)
			(end 0.508 0.9398)
			(stroke
				(width 0.1524)
				(type default)
			)
			(layer "B.SilkS")
		)
		(fp_rect
			(start 0.508 0.9398)
			(end -0.508 -0.9398)
			(stroke
				(width 0)
				(type default)
			)
			(fill no)
			(layer "B.CrtYd")
		)
		(fp_rect
			(start 0.508 0.9398)
			(end -0.508 -0.9398)
			(stroke
				(width 0)
				(type default)
			)
			(fill no)
			(layer "B.Fab")
		)
		(pad "1" smd custom
			(at 0 -0.4445 180)
			(size 0.1397 0.1397)
			(layers "B.Cu" "B.Mask" "B.Paste")
			(net "P1V8_C")
			(options
				(clearance outline)
				(anchor circle)
			)
			(primitives
				(gr_poly
					(pts
						(arc
							(start -0.1778 0.2794)
							(mid -0.249642 0.249642)
							(end -0.2794 0.1778)
						)
						(arc
							(start -0.2794 -0.1778)
							(mid -0.249642 -0.249642)
							(end -0.1778 -0.2794)
						)
						(arc
							(start 0.1778 -0.2794)
							(mid 0.249642 -0.249642)
							(end 0.2794 -0.1778)
						)
						(arc
							(start 0.2794 0.1778)
							(mid 0.249642 0.249642)
							(end 0.1778 0.2794)
						)
					)
					(width 0)
					(fill yes)
				)
			)
		)
		(pad "2" smd custom
			(at 0 0.4445 180)
			(size 0.1397 0.1397)
			(layers "B.Cu" "B.Mask" "B.Paste")
			(net "SIO_CLK_1")
			(options
				(clearance outline)
				(anchor circle)
			)
			(primitives
				(gr_poly
					(pts
						(arc
							(start -0.1778 0.2794)
							(mid -0.249642 0.249642)
							(end -0.2794 0.1778)
						)
						(arc
							(start -0.2794 -0.1778)
							(mid -0.249642 -0.249642)
							(end -0.1778 -0.2794)
						)
						(arc
							(start 0.1778 -0.2794)
							(mid 0.249642 -0.249642)
							(end 0.2794 -0.1778)
						)
						(arc
							(start 0.2794 0.1778)
							(mid 0.249642 0.249642)
							(end 0.1778 0.2794)
						)
					)
					(width 0)
					(fill yes)
				)
			)
		)
	)
)
